# ZAIUS-MB-PVT-X04-BOM_X31_20180131_Final.xls.xlsx — DEPOP_GA (bom)
| FOXCONN TECHNOLOGY GROUP |  |  |  |  |  |  |  |  |  |  |  |  |
| BILL OF MATERIAL |  |  |  |  |  |  |  |  |  |  |  |  |
| REV OF  BOM |  | CUSTOMER | <name> |  | CUSTOMER P/N |  | PRODUCT CODE |  | PWA  REV |  | DATE |  |
| Sourcing (Single/Sole/Multi) | Critical Commodity (Y or N) | Component Class (1, 2, other) | Customer PSL (Y or N) | Item Number | Foxconn P/N | Customer P/N | Part Description | Manufacturer  Full Name | Manufacturer  Part Number | Qty | RoHS Status | Location |
